# T6G (Grand Teton) — schematic netlist excerpt (pin names and nets, part order shuffled) for the footprints in the layout excerpt that follows; sources: Cadence DE-HDL packaged netlist, KiCad conversion of 04192023_DAF0TMB3IC0_F0TG_MB_C_brd_V02_OCP.brd

R8103  Q_RES  8.45K 1% EMPTY  pkg 0402LF  page 242 : A = P3V3_AUX ; B = FM_AC_PWR_BTN_R_N
C2456  Q_CAP  22UF 4V 20% X6S  pkg C0402  page 74 : A = PVDDCR_SOC_P1 ; B = GND

(kicad_pcb
	(version 20260206)
	(generator "pcbnew")
	(generator_version "10.0")
	(general
		(thickness 1.6)
		(legacy_teardrops no)
	)
	(paper "A4")
	(title_block
		(title "04192023_DAF0TMB3IC0_F0TG_MB_C_brd_V02_OCP.brd")
		(comment 1 "Grand Teton / footprints 5127-5128 of 8354")
	)
	(layers
		(0 "F.Cu" signal "TOP")
		(4 "In1.Cu" signal "GND")
		(6 "In2.Cu" signal "IN1")
		(8 "In3.Cu" signal "GND1")
		(10 "In4.Cu" signal "IN2")
		(12 "In5.Cu" signal "GND2")
		(14 "In6.Cu" signal "IN3")
		(16 "In7.Cu" signal "GND3")
		(18 "In8.Cu" signal "VCC")
		(20 "In9.Cu" signal "VCC1")
		(22 "In10.Cu" signal "GND4")
		(24 "In11.Cu" signal "IN4")
		(26 "In12.Cu" signal "GND5")
		(28 "In13.Cu" signal "IN5")
		(30 "In14.Cu" signal "GND6")
		(32 "In15.Cu" signal "IN6")
		(34 "In16.Cu" signal "GND7")
		(2 "B.Cu" signal "BOTTOM")
		(9 "F.Adhes" user "F.Adhesive")
		(11 "B.Adhes" user "B.Adhesive")
		(13 "F.Paste" user "Package Geometry/Pastemask Top")
		(15 "B.Paste" user "Package Geometry/Pastemask Bottom")
		(5 "F.SilkS" user "Ref Des/Silkscreen Top")
		(7 "B.SilkS" user "Ref Des/Silkscreen Bottom")
		(1 "F.Mask" user "Board Geometry/Soldermask Top")
		(3 "B.Mask" user "Board Geometry/Soldermask Bottom")
		(17 "Dwgs.User" user "User.Drawings")
		(19 "Cmts.User" user "User.Comments")
		(21 "Eco1.User" user "User.Eco1")
		(23 "Eco2.User" user "User.Eco2")
		(25 "Edge.Cuts" user "Board Geometry/Outline")
		(27 "Margin" user)
		(31 "F.CrtYd" user "Package Geometry/Place Bound Top")
		(29 "B.CrtYd" user "Package Geometry/Place Bound Bottom")
		(35 "F.Fab" user "Ref Des/Assembly Top")
		(33 "B.Fab" user "Ref Des/Assembly Bottom")
	)
	(footprint ""
		(layer "B.Cu")
		(at 122.861578 -261.93623)
		(property "Reference" "C2456"
			(at 0 0 0)
			(layer "B.SilkS")
			(hide yes)
			(effects
				(font
					(size 1.27 1.27)
				)
				(justify mirror)
			)
		)
		(property "Value" ""
			(at 0 0 0)
			(layer "B.Fab")
			(effects
				(font
					(size 1.27 1.27)
				)
				(justify mirror)
			)
		)
		(duplicate_pad_numbers_are_jumpers no)
		(fp_line
			(start -0.7874 -0.4064)
			(end -0.7874 0.4064)
			(stroke
				(width 0.1524)
				(type default)
			)
			(layer "B.SilkS")
		)
		(fp_line
			(start -0.7874 0.4064)
			(end 0.7874 0.4064)
			(stroke
				(width 0.1524)
				(type default)
			)
			(layer "B.SilkS")
		)
		(fp_line
			(start 0.7874 -0.4064)
			(end -0.7874 -0.4064)
			(stroke
				(width 0.1524)
				(type default)
			)
			(layer "B.SilkS")
		)
		(fp_line
			(start 0.7874 0.4064)
			(end 0.7874 -0.4064)
			(stroke
				(width 0.1524)
				(type default)
			)
			(layer "B.SilkS")
		)
		(fp_line
			(start -0.67945 -0.3048)
			(end -0.67945 0.3048)
			(stroke
				(width 0.1)
				(type default)
			)
			(layer "B.Fab")
		)
		(fp_line
			(start -0.67945 0.3048)
			(end -0.120396 0.3048)
			(stroke
				(width 0.1)
				(type default)
			)
			(layer "B.Fab")
		)
		(fp_line
			(start -0.12065 -0.3048)
			(end -0.67945 -0.3048)
			(stroke
				(width 0.1)
				(type default)
			)
			(layer "B.Fab")
		)
		(fp_line
			(start -0.12065 -0.2794)
			(end -0.12065 -0.3048)
			(stroke
				(width 0.1)
				(type default)
			)
			(layer "B.Fab")
		)
		(fp_line
			(start -0.120396 0.2794)
			(end 0.12065 0.2794)
			(stroke
				(width 0.1)
				(type default)
			)
			(layer "B.Fab")
		)
		(fp_line
			(start -0.120396 0.3048)
			(end -0.120396 0.2794)
			(stroke
				(width 0.1)
				(type default)
			)
			(layer "B.Fab")
		)
		(fp_line
			(start 0.12065 -0.305054)
			(end 0.12065 -0.2794)
			(stroke
				(width 0.1)
				(type default)
			)
			(layer "B.Fab")
		)
		(fp_line
			(start 0.12065 -0.2794)
			(end -0.12065 -0.2794)
			(stroke
				(width 0.1)
				(type default)
			)
			(layer "B.Fab")
		)
		(fp_line
			(start 0.12065 0.2794)
			(end 0.12065 0.3048)
			(stroke
				(width 0.1)
				(type default)
			)
			(layer "B.Fab")
		)
		(fp_line
			(start 0.12065 0.3048)
			(end 0.67945 0.3048)
			(stroke
				(width 0.1)
				(type default)
			)
			(layer "B.Fab")
		)
		(fp_line
			(start 0.67945 -0.305054)
			(end 0.12065 -0.305054)
			(stroke
				(width 0.1)
				(type default)
			)
			(layer "B.Fab")
		)
		(fp_line
			(start 0.67945 0.3048)
			(end 0.67945 -0.305054)
			(stroke
				(width 0.1)
				(type default)
			)
			(layer "B.Fab")
		)
		(pad "1" smd circle
			(at 0.40005 0 180)
			(size 0 0)
			(layers "B.Cu" "B.Mask" "B.Paste")
			(net "PVDDCR_SOC_P1")
		)
		(pad "2" smd circle
			(at -0.40005 0 180)
			(size 0 0)
			(layers "B.Cu" "B.Mask" "B.Paste")
			(net "GND")
		)
	)
	(footprint ""
		(layer "B.Cu")
		(at 198.374 -144.272 -90)
		(property "Reference" "R8103"
			(at 0 0 90)
			(layer "B.SilkS")
			(hide yes)
			(effects
				(font
					(size 1.27 1.27)
				)
				(justify mirror)
			)
		)
		(property "Value" ""
			(at 0 0 90)
			(layer "B.Fab")
			(effects
				(font
					(size 1.27 1.27)
				)
				(justify mirror)
			)
		)
		(duplicate_pad_numbers_are_jumpers no)
		(fp_line
			(start -0.7874 0.4064)
			(end 0.7874 0.4064)
			(stroke
				(width 0.1524)
				(type default)
			)
			(layer "B.SilkS")
		)
		(fp_line
			(start 0.7874 0.4064)
			(end 0.7874 -0.4064)
			(stroke
				(width 0.1524)
				(type default)
			)
			(layer "B.SilkS")
		)
		(fp_line
			(start -0.7874 -0.4064)
			(end -0.7874 0.4064)
			(stroke
				(width 0.1524)
				(type default)
			)
			(layer "B.SilkS")
		)
		(fp_line
			(start 0.7874 -0.4064)
			(end -0.7874 -0.4064)
			(stroke
				(width 0.1524)
				(type default)
			)
			(layer "B.SilkS")
		)
		(fp_line
			(start -0.67945 0.3048)
			(end -0.120396 0.3048)
			(stroke
				(width 0.1)
				(type default)
			)
			(layer "B.Fab")
		)
		(fp_line
			(start -0.120396 0.3048)
			(end -0.120396 0.2794)
			(stroke
				(width 0.1)
				(type default)
			)
			(layer "B.Fab")
		)
		(fp_line
			(start 0.12065 0.3048)
			(end 0.67945 0.3048)
			(stroke
				(width 0.1)
				(type default)
			)
			(layer "B.Fab")
		)
		(fp_line
			(start 0.67945 0.3048)
			(end 0.67945 -0.305054)
			(stroke
				(width 0.1)
				(type default)
			)
			(layer "B.Fab")
		)
		(fp_line
			(start -0.120396 0.2794)
			(end 0.12065 0.2794)
			(stroke
				(width 0.1)
				(type default)
			)
			(layer "B.Fab")
		)
		(fp_line
			(start 0.12065 0.2794)
			(end 0.12065 0.3048)
			(stroke
				(width 0.1)
				(type default)
			)
			(layer "B.Fab")
		)
		(fp_line
			(start -0.12065 -0.2794)
			(end -0.12065 -0.3048)
			(stroke
				(width 0.1)
				(type default)
			)
			(layer "B.Fab")
		)
		(fp_line
			(start 0.12065 -0.2794)
			(end -0.12065 -0.2794)
			(stroke
				(width 0.1)
				(type default)
			)
			(layer "B.Fab")
		)
		(fp_line
			(start -0.67945 -0.3048)
			(end -0.67945 0.3048)
			(stroke
				(width 0.1)
				(type default)
			)
			(layer "B.Fab")
		)
		(fp_line
			(start -0.12065 -0.3048)
			(end -0.67945 -0.3048)
			(stroke
				(width 0.1)
				(type default)
			)
			(layer "B.Fab")
		)
		(fp_line
			(start 0.12065 -0.305054)
			(end 0.12065 -0.2794)
			(stroke
				(width 0.1)
				(type default)
			)
			(layer "B.Fab")
		)
		(fp_line
			(start 0.67945 -0.305054)
			(end 0.12065 -0.305054)
			(stroke
				(width 0.1)
				(type default)
			)
			(layer "B.Fab")
		)
		(pad "1" smd circle
			(at 0.40005 0 90)
			(size 0 0)
			(layers "B.Cu" "B.Mask" "B.Paste")
			(net "P3V3_AUX")
		)
		(pad "2" smd circle
			(at -0.40005 0 90)
			(size 0 0)
			(layers "B.Cu" "B.Mask" "B.Paste")
			(net "FM_AC_PWR_BTN_R_N")
		)
	)
)
